# BASEBOARD_FAB2 (Tioga Pass) — schematic netlist excerpt (pin names and nets, part order shuffled) for the footprints in the layout excerpt that follows; sources: Cadence DE-HDL packaged netlist, KiCad conversion of Wiwynn_Tioga_Pass_MB.brd

R6P32  RES  2.0K 1% EMPTY  pkg 0402  page 201 : A = P3V3_STBY ; B = SMB_VR_STBY_LVC3_SDA
C9P5  CAPP  470UF 2.5V 20% ALUM  pkg 3018  page 208 : A = PVCCIN_CPU1 ; B = GND
R1L31  RES  200.0 1% CHIP  pkg 0402  page 175 : A = FP_PWR_BTN_R_N ; B = FP_PWR_BTN_R1_N

(kicad_pcb
	(version 20260206)
	(generator "pcbnew")
	(generator_version "10.0")
	(general
		(thickness 1.6)
		(legacy_teardrops no)
	)
	(paper "A4")
	(title_block
		(title "Wiwynn_Tioga_Pass_MB.brd")
		(comment 1 "Tioga Pass / footprints 4373-4375 of 4770")
	)
	(layers
		(0 "F.Cu" signal "TOP")
		(4 "In1.Cu" signal "L2GND")
		(6 "In2.Cu" signal "L3")
		(8 "In3.Cu" signal "L4GND")
		(10 "In4.Cu" signal "L5")
		(12 "In5.Cu" signal "L6GND")
		(14 "In6.Cu" signal "L7VCC")
		(16 "In7.Cu" signal "L8VCC")
		(18 "In8.Cu" signal "L9GND")
		(20 "In9.Cu" signal "L10")
		(22 "In10.Cu" signal "L11GND")
		(24 "In11.Cu" signal "L12")
		(26 "In12.Cu" signal "L13GND")
		(2 "B.Cu" signal "BOTTOM")
		(9 "F.Adhes" user "F.Adhesive")
		(11 "B.Adhes" user "B.Adhesive")
		(13 "F.Paste" user "Package Geometry/Pastemask Top")
		(15 "B.Paste" user "Package Geometry/Pastemask Bottom")
		(5 "F.SilkS" user "Ref Des/Silkscreen Top")
		(7 "B.SilkS" user "Ref Des/Silkscreen Bottom")
		(1 "F.Mask" user "Board Geometry/Soldermask Top")
		(3 "B.Mask" user "Board Geometry/Soldermask Bottom")
		(17 "Dwgs.User" user "User.Drawings")
		(19 "Cmts.User" user "User.Comments")
		(21 "Eco1.User" user "User.Eco1")
		(23 "Eco2.User" user "User.Eco2")
		(25 "Edge.Cuts" user "Board Geometry/Outline")
		(27 "Margin" user)
		(31 "F.CrtYd" user "Package Geometry/Place Bound Top")
		(29 "B.CrtYd" user "Package Geometry/Place Bound Bottom")
		(35 "F.Fab" user "Ref Des/Assembly Top")
		(33 "B.Fab" user "Ref Des/Assembly Bottom")
	)
	(footprint ""
		(layer "B.Cu")
		(at 471.3605 -137.795 -90)
		(property "Reference" "R1L31"
			(at 0 0 90)
			(layer "B.SilkS")
			(hide yes)
			(effects
				(font
					(size 1.27 1.27)
				)
				(justify mirror)
			)
		)
		(property "Value" ""
			(at 0 0 90)
			(layer "B.Fab")
			(effects
				(font
					(size 1.27 1.27)
				)
				(justify mirror)
			)
		)
		(duplicate_pad_numbers_are_jumpers no)
		(fp_poly
			(pts
				(xy 0.2794 -0.1016) (xy -0.2794 -0.1016) (xy -0.2794 0.9906) (xy 0.2794 0.9906)
			)
			(stroke
				(width 0)
				(type default)
			)
			(fill no)
			(layer "B.CrtYd")
		)
		(fp_line
			(start -0.2794 0.9906)
			(end -0.2794 -0.1016)
			(stroke
				(width 0.1)
				(type default)
			)
			(layer "B.Fab")
		)
		(fp_line
			(start 0.2794 0.9906)
			(end -0.2794 0.9906)
			(stroke
				(width 0.1)
				(type default)
			)
			(layer "B.Fab")
		)
		(fp_line
			(start -0.2794 -0.1016)
			(end 0.2794 -0.1016)
			(stroke
				(width 0.1)
				(type default)
			)
			(layer "B.Fab")
		)
		(fp_line
			(start 0.2794 -0.1016)
			(end 0.2794 0.9906)
			(stroke
				(width 0.1)
				(type default)
			)
			(layer "B.Fab")
		)
		(pad "1" smd rect
			(at 0 0 90)
			(size 0.508 0.508)
			(layers "B.Cu" "B.Mask" "B.Paste")
			(net "FP_PWR_BTN_R_N")
		)
		(pad "2" smd rect
			(at 0 0.889 90)
			(size 0.508 0.508)
			(layers "B.Cu" "B.Mask" "B.Paste")
			(net "FP_PWR_BTN_R1_N")
		)
		(zone
			(layer "B.Cu")
			(hatch none 0.5)
			(connect_pads
				(clearance 0)
			)
			(min_thickness 0.25)
			(keepout
				(tracks not_allowed)
				(vias allowed)
				(pads allowed)
				(copperpour not_allowed)
				(footprints allowed)
			)
			(placement
				(enabled no)
				(sheetname "")
			)
			(fill
				(thermal_gap 0.5)
				(thermal_bridge_width 0.5)
				(island_removal_mode 0)
			)
			(polygon
				(pts
					(xy 470.7255 -137.541) (xy 470.7255 -138.049) (xy 471.1065 -138.049) (xy 471.1065 -137.541)
				)
			)
		)
		(zone
			(layer "B.Cu")
			(hatch none 0.5)
			(connect_pads
				(clearance 0)
			)
			(min_thickness 0.25)
			(keepout
				(tracks allowed)
				(vias not_allowed)
				(pads allowed)
				(copperpour not_allowed)
				(footprints allowed)
			)
			(placement
				(enabled no)
				(sheetname "")
			)
			(fill
				(thermal_gap 0.5)
				(thermal_bridge_width 0.5)
				(island_removal_mode 0)
			)
			(polygon
				(pts
					(xy 471.1065 -137.541) (xy 471.1065 -138.049) (xy 470.7255 -138.049) (xy 470.7255 -137.541)
				)
			)
		)
	)
	(footprint ""
		(layer "B.Cu")
		(at 45.212 -83.947 -90)
		(property "Reference" "C9P5"
			(at 0.78867 -3.556 0)
			(unlocked yes)
			(layer "B.SilkS")
			(effects
				(font
					(size 0.7874 0.5842)
					(thickness 0.1524)
				)
				(justify mirror)
			)
		)
		(property "Value" ""
			(at 0 0 90)
			(layer "B.Fab")
			(effects
				(font
					(size 1.27 1.27)
				)
				(justify mirror)
			)
		)
		(duplicate_pad_numbers_are_jumpers no)
		(fp_line
			(start -2.286 7.366)
			(end -1.600708 7.366)
			(stroke
				(width 0.1524)
				(type default)
			)
			(layer "B.SilkS")
		)
		(fp_line
			(start -2.286 7.366)
			(end -2.286 1.63195)
			(stroke
				(width 0.1524)
				(type default)
			)
			(layer "B.SilkS")
		)
		(fp_line
			(start 2.286 7.366)
			(end 1.60147 7.366)
			(stroke
				(width 0.1524)
				(type default)
			)
			(layer "B.SilkS")
		)
		(fp_line
			(start 2.286 7.366)
			(end 2.286 1.632712)
			(stroke
				(width 0.1524)
				(type default)
			)
			(layer "B.SilkS")
		)
		(fp_line
			(start -2.504948 1.633728)
			(end -1.6002 1.633728)
			(stroke
				(width 0.1524)
				(type default)
			)
			(layer "B.SilkS")
		)
		(fp_line
			(start 2.563114 1.633728)
			(end 1.6002 1.633728)
			(stroke
				(width 0.1524)
				(type default)
			)
			(layer "B.SilkS")
		)
		(fp_line
			(start -2.504948 -1.616456)
			(end -2.504948 1.633728)
			(stroke
				(width 0.1524)
				(type default)
			)
			(layer "B.SilkS")
		)
		(fp_line
			(start -1.6002 -1.616456)
			(end -2.504948 -1.616456)
			(stroke
				(width 0.1524)
				(type default)
			)
			(layer "B.SilkS")
		)
		(fp_line
			(start 1.6002 -1.616456)
			(end 2.563114 -1.616456)
			(stroke
				(width 0.1524)
				(type default)
			)
			(layer "B.SilkS")
		)
		(fp_line
			(start 2.563114 -1.616456)
			(end 2.563114 1.633728)
			(stroke
				(width 0.1524)
				(type default)
			)
			(layer "B.SilkS")
		)
		(fp_rect
			(start 2.286 7.366)
			(end -2.286 -0.254)
			(stroke
				(width 0)
				(type default)
			)
			(fill no)
			(layer "B.CrtYd")
		)
		(fp_line
			(start -2.286 7.366)
			(end 2.286 7.366)
			(stroke
				(width 0.1)
				(type default)
			)
			(layer "B.Fab")
		)
		(fp_line
			(start 2.286 7.366)
			(end 2.286 -0.254)
			(stroke
				(width 0.1)
				(type default)
			)
			(layer "B.Fab")
		)
		(fp_line
			(start -2.286 -0.254)
			(end -2.286 7.366)
			(stroke
				(width 0.1)
				(type default)
			)
			(layer "B.Fab")
		)
		(fp_line
			(start 2.286 -0.254)
			(end -2.286 -0.254)
			(stroke
				(width 0.1)
				(type default)
			)
			(layer "B.Fab")
		)
		(pad "1" smd rect
			(at 0 0 90)
			(size 2.54 3.048)
			(layers "B.Cu" "B.Mask" "B.Paste")
			(net "PVCCIN_CPU1")
		)
		(pad "2" smd rect
			(at 0 7.112 90)
			(size 2.54 3.048)
			(layers "B.Cu" "B.Mask" "B.Paste")
			(net "GND")
		)
	)
	(footprint ""
		(layer "B.Cu")
		(at 179.199794 -69.230494 -90)
		(property "Reference" "R6P32"
			(at 0 0 90)
			(layer "B.SilkS")
			(hide yes)
			(effects
				(font
					(size 1.27 1.27)
				)
				(justify mirror)
			)
		)
		(property "Value" ""
			(at 0 0 90)
			(layer "B.Fab")
			(effects
				(font
					(size 1.27 1.27)
				)
				(justify mirror)
			)
		)
		(duplicate_pad_numbers_are_jumpers no)
		(fp_rect
			(start 0.2794 0.9906)
			(end -0.2794 -0.1016)
			(stroke
				(width 0)
				(type default)
			)
			(fill no)
			(layer "B.CrtYd")
		)
		(fp_line
			(start -0.2794 0.9906)
			(end -0.2794 -0.1016)
			(stroke
				(width 0.1)
				(type default)
			)
			(layer "B.Fab")
		)
		(fp_line
			(start 0.2794 0.9906)
			(end -0.2794 0.9906)
			(stroke
				(width 0.1)
				(type default)
			)
			(layer "B.Fab")
		)
		(fp_line
			(start -0.2794 -0.1016)
			(end 0.2794 -0.1016)
			(stroke
				(width 0.1)
				(type default)
			)
			(layer "B.Fab")
		)
		(fp_line
			(start 0.2794 -0.1016)
			(end 0.2794 0.9906)
			(stroke
				(width 0.1)
				(type default)
			)
			(layer "B.Fab")
		)
		(pad "1" smd rect
			(at 0 0 90)
			(size 0.508 0.508)
			(layers "B.Cu" "B.Mask" "B.Paste")
			(net "P3V3_STBY")
		)
		(pad "2" smd rect
			(at 0 0.889 90)
			(size 0.508 0.508)
			(layers "B.Cu" "B.Mask" "B.Paste")
			(net "SMB_VR_STBY_LVC3_SDA")
		)
		(zone
			(layer "B.Cu")
			(hatch none 0.5)
			(connect_pads
				(clearance 0)
			)
			(min_thickness 0.25)
			(keepout
				(tracks not_allowed)
				(vias allowed)
				(pads allowed)
				(copperpour not_allowed)
				(footprints allowed)
			)
			(placement
				(enabled no)
				(sheetname "")
			)
			(fill
				(thermal_gap 0.5)
				(thermal_bridge_width 0.5)
				(island_removal_mode 0)
			)
			(polygon
				(pts
					(xy 178.564794 -68.976494) (xy 178.945794 -68.976494) (xy 178.945794 -69.484494) (xy 178.564794 -69.484494)
				)
			)
		)
		(zone
			(layer "B.Cu")
			(hatch none 0.5)
			(connect_pads
				(clearance 0)
			)
			(min_thickness 0.25)
			(keepout
				(tracks allowed)
				(vias not_allowed)
				(pads allowed)
				(copperpour not_allowed)
				(footprints allowed)
			)
			(placement
				(enabled no)
				(sheetname "")
			)
			(fill
				(thermal_gap 0.5)
				(thermal_bridge_width 0.5)
				(island_removal_mode 0)
			)
			(polygon
				(pts
					(xy 178.564794 -68.976494) (xy 178.945794 -68.976494) (xy 178.945794 -69.484494) (xy 178.564794 -69.484494)
				)
			)
		)
	)
)
